# SCM (Grand Teton) — schematic netlist excerpt (pin names and nets, part order shuffled) for the footprints in the layout excerpt that follows; sources: Cadence DE-HDL packaged netlist, KiCad conversion of 12092022_DA0F0TMDCD0_F0T_Management_Board_D_brd_V3_OCP.brd

R279  Q_RES  0 5% CHIP  pkg 0402LF  page 17 : A = P1V0_AUX ; B = P1V2_P1V0_I3C_VDDL1
R402  Q_RES  33.2 1% CHIP  pkg 0402LF  page 13 : A = PU_FWSPIWP_N ; B = PU_FWSPIWP_N_R

(kicad_pcb
	(version 20260206)
	(generator "pcbnew")
	(generator_version "10.0")
	(general
		(thickness 1.6)
		(legacy_teardrops no)
	)
	(paper "A4")
	(title_block
		(title "12092022_DA0F0TMDCD0_F0T_Management_Board_D_brd_V3_OCP.brd")
		(comment 1 "Grand Teton / footprints 986-987 of 1440")
	)
	(layers
		(0 "F.Cu" signal "TOP")
		(4 "In1.Cu" signal "GND")
		(6 "In2.Cu" signal "IN1")
		(8 "In3.Cu" signal "GND1")
		(10 "In4.Cu" signal "IN2")
		(12 "In5.Cu" signal "VCC")
		(14 "In6.Cu" signal "VCC1")
		(16 "In7.Cu" signal "IN3")
		(18 "In8.Cu" signal "GND2")
		(20 "In9.Cu" signal "IN4")
		(22 "In10.Cu" signal "GND3")
		(2 "B.Cu" signal "BOTTOM")
		(9 "F.Adhes" user "F.Adhesive")
		(11 "B.Adhes" user "B.Adhesive")
		(13 "F.Paste" user "Package Geometry/Pastemask Top")
		(15 "B.Paste" user "Package Geometry/Pastemask Bottom")
		(5 "F.SilkS" user "Ref Des/Silkscreen Top")
		(7 "B.SilkS" user "Ref Des/Silkscreen Bottom")
		(1 "F.Mask" user "Board Geometry/Soldermask Top")
		(3 "B.Mask" user "Board Geometry/Soldermask Bottom")
		(17 "Dwgs.User" user "User.Drawings")
		(19 "Cmts.User" user "User.Comments")
		(21 "Eco1.User" user "User.Eco1")
		(23 "Eco2.User" user "User.Eco2")
		(25 "Edge.Cuts" user "Board Geometry/Outline")
		(27 "Margin" user)
		(31 "F.CrtYd" user "Package Geometry/Place Bound Top")
		(29 "B.CrtYd" user "Package Geometry/Place Bound Bottom")
		(35 "F.Fab" user "Ref Des/Assembly Top")
		(33 "B.Fab" user "Ref Des/Assembly Bottom")
	)
	(footprint ""
		(layer "B.Cu")
		(at 56.7436 -67.818 -90)
		(property "Reference" "R402"
			(at 0 0 90)
			(layer "B.SilkS")
			(hide yes)
			(effects
				(font
					(size 1.27 1.27)
				)
				(justify mirror)
			)
		)
		(property "Value" ""
			(at 0 0 90)
			(layer "B.Fab")
			(effects
				(font
					(size 1.27 1.27)
				)
				(justify mirror)
			)
		)
		(duplicate_pad_numbers_are_jumpers no)
		(fp_line
			(start -0.7874 0.4064)
			(end 0.7874 0.4064)
			(stroke
				(width 0.1524)
				(type default)
			)
			(layer "B.SilkS")
		)
		(fp_line
			(start 0.7874 0.4064)
			(end 0.7874 -0.4064)
			(stroke
				(width 0.1524)
				(type default)
			)
			(layer "B.SilkS")
		)
		(fp_line
			(start -0.7874 -0.4064)
			(end -0.7874 0.4064)
			(stroke
				(width 0.1524)
				(type default)
			)
			(layer "B.SilkS")
		)
		(fp_line
			(start 0.7874 -0.4064)
			(end -0.7874 -0.4064)
			(stroke
				(width 0.1524)
				(type default)
			)
			(layer "B.SilkS")
		)
		(fp_line
			(start -0.67945 0.3048)
			(end -0.120396 0.3048)
			(stroke
				(width 0.1)
				(type default)
			)
			(layer "B.Fab")
		)
		(fp_line
			(start -0.120396 0.3048)
			(end -0.120396 0.2794)
			(stroke
				(width 0.1)
				(type default)
			)
			(layer "B.Fab")
		)
		(fp_line
			(start 0.12065 0.3048)
			(end 0.67945 0.3048)
			(stroke
				(width 0.1)
				(type default)
			)
			(layer "B.Fab")
		)
		(fp_line
			(start 0.67945 0.3048)
			(end 0.67945 -0.305054)
			(stroke
				(width 0.1)
				(type default)
			)
			(layer "B.Fab")
		)
		(fp_line
			(start -0.120396 0.2794)
			(end 0.12065 0.2794)
			(stroke
				(width 0.1)
				(type default)
			)
			(layer "B.Fab")
		)
		(fp_line
			(start 0.12065 0.2794)
			(end 0.12065 0.3048)
			(stroke
				(width 0.1)
				(type default)
			)
			(layer "B.Fab")
		)
		(fp_line
			(start -0.12065 -0.2794)
			(end -0.12065 -0.3048)
			(stroke
				(width 0.1)
				(type default)
			)
			(layer "B.Fab")
		)
		(fp_line
			(start 0.12065 -0.2794)
			(end -0.12065 -0.2794)
			(stroke
				(width 0.1)
				(type default)
			)
			(layer "B.Fab")
		)
		(fp_line
			(start -0.67945 -0.3048)
			(end -0.67945 0.3048)
			(stroke
				(width 0.1)
				(type default)
			)
			(layer "B.Fab")
		)
		(fp_line
			(start -0.12065 -0.3048)
			(end -0.67945 -0.3048)
			(stroke
				(width 0.1)
				(type default)
			)
			(layer "B.Fab")
		)
		(fp_line
			(start 0.12065 -0.305054)
			(end 0.12065 -0.2794)
			(stroke
				(width 0.1)
				(type default)
			)
			(layer "B.Fab")
		)
		(fp_line
			(start 0.67945 -0.305054)
			(end 0.12065 -0.305054)
			(stroke
				(width 0.1)
				(type default)
			)
			(layer "B.Fab")
		)
		(pad "1" smd circle
			(at 0.40005 0 90)
			(size 0 0)
			(layers "B.Cu" "B.Mask" "B.Paste")
			(net "PU_FWSPIWP_N")
		)
		(pad "2" smd circle
			(at -0.40005 0 90)
			(size 0 0)
			(layers "B.Cu" "B.Mask" "B.Paste")
			(net "PU_FWSPIWP_N_R")
		)
	)
	(footprint ""
		(layer "B.Cu")
		(at 39.742618 -52.779676 -90)
		(property "Reference" "R279"
			(at 0 0 90)
			(layer "B.SilkS")
			(hide yes)
			(effects
				(font
					(size 1.27 1.27)
				)
				(justify mirror)
			)
		)
		(property "Value" ""
			(at 0 0 90)
			(layer "B.Fab")
			(effects
				(font
					(size 1.27 1.27)
				)
				(justify mirror)
			)
		)
		(duplicate_pad_numbers_are_jumpers no)
		(fp_line
			(start -0.7874 0.4064)
			(end 0.7874 0.4064)
			(stroke
				(width 0.1524)
				(type default)
			)
			(layer "B.SilkS")
		)
		(fp_line
			(start 0.7874 0.4064)
			(end 0.7874 -0.4064)
			(stroke
				(width 0.1524)
				(type default)
			)
			(layer "B.SilkS")
		)
		(fp_line
			(start -0.7874 -0.4064)
			(end -0.7874 0.4064)
			(stroke
				(width 0.1524)
				(type default)
			)
			(layer "B.SilkS")
		)
		(fp_line
			(start 0.7874 -0.4064)
			(end -0.7874 -0.4064)
			(stroke
				(width 0.1524)
				(type default)
			)
			(layer "B.SilkS")
		)
		(fp_line
			(start -0.67945 0.3048)
			(end -0.120396 0.3048)
			(stroke
				(width 0.1)
				(type default)
			)
			(layer "B.Fab")
		)
		(fp_line
			(start -0.120396 0.3048)
			(end -0.120396 0.2794)
			(stroke
				(width 0.1)
				(type default)
			)
			(layer "B.Fab")
		)
		(fp_line
			(start 0.12065 0.3048)
			(end 0.67945 0.3048)
			(stroke
				(width 0.1)
				(type default)
			)
			(layer "B.Fab")
		)
		(fp_line
			(start 0.67945 0.3048)
			(end 0.67945 -0.305054)
			(stroke
				(width 0.1)
				(type default)
			)
			(layer "B.Fab")
		)
		(fp_line
			(start -0.120396 0.2794)
			(end 0.12065 0.2794)
			(stroke
				(width 0.1)
				(type default)
			)
			(layer "B.Fab")
		)
		(fp_line
			(start 0.12065 0.2794)
			(end 0.12065 0.3048)
			(stroke
				(width 0.1)
				(type default)
			)
			(layer "B.Fab")
		)
		(fp_line
			(start -0.12065 -0.2794)
			(end -0.12065 -0.3048)
			(stroke
				(width 0.1)
				(type default)
			)
			(layer "B.Fab")
		)
		(fp_line
			(start 0.12065 -0.2794)
			(end -0.12065 -0.2794)
			(stroke
				(width 0.1)
				(type default)
			)
			(layer "B.Fab")
		)
		(fp_line
			(start -0.67945 -0.3048)
			(end -0.67945 0.3048)
			(stroke
				(width 0.1)
				(type default)
			)
			(layer "B.Fab")
		)
		(fp_line
			(start -0.12065 -0.3048)
			(end -0.67945 -0.3048)
			(stroke
				(width 0.1)
				(type default)
			)
			(layer "B.Fab")
		)
		(fp_line
			(start 0.12065 -0.305054)
			(end 0.12065 -0.2794)
			(stroke
				(width 0.1)
				(type default)
			)
			(layer "B.Fab")
		)
		(fp_line
			(start 0.67945 -0.305054)
			(end 0.12065 -0.305054)
			(stroke
				(width 0.1)
				(type default)
			)
			(layer "B.Fab")
		)
		(pad "1" smd circle
			(at 0.40005 0 90)
			(size 0 0)
			(layers "B.Cu" "B.Mask" "B.Paste")
			(net "P1V0_AUX")
		)
		(pad "2" smd circle
			(at -0.40005 0 90)
			(size 0 0)
			(layers "B.Cu" "B.Mask" "B.Paste")
			(net "P1V2_P1V0_I3C_VDDL1")
		)
	)
)
